(kicad_pcb
	(version 20260206)
	(generator "pcbnew")
	(generator_version "10.0")
	(general
		(thickness 1.6)
		(legacy_teardrops no)
	)
	(paper "A4")
	(title_block
		(title "panther-plus-userver — 13130-1b_20150205.brd")
		(comment 1 "Honey Badger (Wiwynn) / footprint 624 of 1509 (DIMM4), pads 1-8 of 210")
	)
	(layers
		(0 "F.Cu" signal "TOP")
		(4 "In1.Cu" signal "L2")
		(6 "In2.Cu" signal "L3")
		(8 "In3.Cu" signal "L4")
		(10 "In4.Cu" signal "L5")
		(12 "In5.Cu" signal "L6")
		(14 "In6.Cu" signal "L7")
		(16 "In7.Cu" signal "L8")
		(18 "In8.Cu" signal "L9")
		(20 "In9.Cu" signal "L10")
		(22 "In10.Cu" signal "L11")
		(2 "B.Cu" signal "BOTTOM")
		(9 "F.Adhes" user "F.Adhesive")
		(11 "B.Adhes" user "B.Adhesive")
		(13 "F.Paste" user "Package Geometry/Pastemask Top")
		(15 "B.Paste" user "Package Geometry/Pastemask Bottom")
		(5 "F.SilkS" user "Ref Des/Silkscreen Top")
		(7 "B.SilkS" user "Ref Des/Silkscreen Bottom")
		(1 "F.Mask" user "Board Geometry/Soldermask Top")
		(3 "B.Mask" user "Board Geometry/Soldermask Bottom")
		(17 "Dwgs.User" user "User.Drawings")
		(19 "Cmts.User" user "User.Comments")
		(21 "Eco1.User" user "User.Eco1")
		(23 "Eco2.User" user "User.Eco2")
		(25 "Edge.Cuts" user "Board Geometry/Outline")
		(27 "Margin" user)
		(31 "F.CrtYd" user "Package Geometry/Place Bound Top")
		(29 "B.CrtYd" user "Package Geometry/Place Bound Bottom")
		(35 "F.Fab" user "Ref Des/Assembly Top")
		(33 "B.Fab" user "Ref Des/Assembly Bottom")
	)
	(footprint ""
		(layer "F.Cu")
		(at 159.999934 -5.790692)
		(property "Reference" "DIMM4"
			(at 0 0 0)
			(layer "F.SilkS")
			(hide yes)
			(effects
				(font
					(size 1.27 1.27)
				)
			)
		)
		(property "Value" "DDR3-204P-174-COLAY-1-GP"
			(at -40.682164 -17.468088 0)
			(unlocked yes)
			(layer "F.Fab")
			(hide yes)
			(effects
				(font
					(size 1.016 1.016)
					(thickness 0.1524)
				)
			)
		)
		(property "Device Type" "AS0A626-H8SN-7H-COLAY-1"
			(at -40.682164 -18.992088 0)
			(unlocked yes)
			(layer "F.Fab")
			(hide yes)
			(effects
				(font
					(size 1.016 1.016)
					(thickness 0.1524)
				)
			)
		)
		(duplicate_pad_numbers_are_jumpers no)
		(pad "" np_thru_hole circle
			(at -33.399984 0)
			(size 0.254 0.254)
			(drill 1.6002)
			(layers "*.Cu" "*.Mask")
			(clearance 1.0287)
			(thermal_gap 1.0287)
		)
		(pad "" np_thru_hole circle
			(at 33.399984 0)
			(size 0.254 0.254)
			(drill 1.1176)
			(layers "*.Cu" "*.Mask")
			(clearance 0.7874)
			(thermal_gap 0.7874)
		)
		(pad "1" smd custom
			(at -31.649924 4.106672)
			(size 0.1143 0.1143)
			(layers "F.Cu" "F.Mask" "F.Paste")
			(net "DDR3_M_B_VREF_DQ1")
			(options
				(clearance outline)
				(anchor circle)
			)
			(primitives
				(gr_poly
					(pts
						(xy 0 0.9017) (xy -0.03175 0.89916) (xy -0.0635 0.889) (xy -0.09144 0.87376) (xy -0.11684 0.85344)
						(xy -0.13716 0.82804) (xy -0.1524 0.8001) (xy -0.16256 0.76835) (xy -0.1651 0.7366) (xy -0.1651 -0.13462)
						(xy -0.17272 -0.14224) (xy -0.19812 -0.1778) (xy -0.2032 -0.18796) (xy -0.20701 -0.19685) (xy -0.21209 -0.20701)
						(xy -0.2159 -0.21717) (xy -0.21844 -0.22733) (xy -0.22225 -0.23876) (xy -0.22352 -0.24892) (xy -0.22606 -0.25908)
						(xy -0.22733 -0.27051) (xy -0.22733 -0.28067) (xy -0.2286 -0.2921) (xy -0.22733 -0.30353) (xy -0.22733 -0.31369)
						(xy -0.22606 -0.32512) (xy -0.22352 -0.33528) (xy -0.22225 -0.34544) (xy -0.21844 -0.35687) (xy -0.2159 -0.36703)
						(xy -0.21209 -0.37719) (xy -0.20701 -0.38735) (xy -0.2032 -0.39624) (xy -0.19812 -0.4064) (xy -0.17272 -0.44196)
						(xy -0.1651 -0.44958) (xy -0.1651 -0.7366) (xy -0.16256 -0.76835) (xy -0.1524 -0.8001) (xy -0.13716 -0.82804)
						(xy -0.11684 -0.85344) (xy -0.09144 -0.87376) (xy -0.0635 -0.889) (xy -0.03175 -0.89916) (xy 0 -0.9017)
						(xy 0.03175 -0.89916) (xy 0.0635 -0.889) (xy 0.09144 -0.87376) (xy 0.11684 -0.85344) (xy 0.13716 -0.82804)
						(xy 0.1524 -0.8001) (xy 0.16256 -0.76835) (xy 0.1651 -0.7366) (xy 0.1651 -0.44958) (xy 0.17272 -0.44196)
						(xy 0.19812 -0.4064) (xy 0.2032 -0.39624) (xy 0.20701 -0.38735) (xy 0.21209 -0.37719) (xy 0.2159 -0.36703)
						(xy 0.21844 -0.35687) (xy 0.22225 -0.34544) (xy 0.22352 -0.33528) (xy 0.22606 -0.32512) (xy 0.22733 -0.31369)
						(xy 0.22733 -0.30353) (xy 0.2286 -0.2921) (xy 0.22733 -0.28067) (xy 0.22733 -0.27051) (xy 0.22606 -0.25908)
						(xy 0.22352 -0.24892) (xy 0.22225 -0.23876) (xy 0.21844 -0.22733) (xy 0.2159 -0.21717) (xy 0.21209 -0.20701)
						(xy 0.20701 -0.19685) (xy 0.2032 -0.18796) (xy 0.19812 -0.1778) (xy 0.17272 -0.14224) (xy 0.1651 -0.13462)
						(xy 0.1651 0.7366) (xy 0.16256 0.76835) (xy 0.1524 0.8001) (xy 0.13716 0.82804) (xy 0.11684 0.85344)
						(xy 0.09144 0.87376) (xy 0.0635 0.889) (xy 0.03175 0.89916)
					)
					(width 0)
					(fill yes)
				)
			)
		)
		(pad "2" smd custom
			(at -31.34995 -4.106672)
			(size 0.1143 0.1143)
			(layers "F.Cu" "F.Mask" "F.Paste")
			(net "GND")
			(options
				(clearance outline)
				(anchor circle)
			)
			(primitives
				(gr_poly
					(pts
						(xy 0 0.9017) (xy -0.03175 0.89916) (xy -0.0635 0.889) (xy -0.09144 0.87376) (xy -0.11684 0.85344)
						(xy -0.13716 0.82804) (xy -0.1524 0.8001) (xy -0.16256 0.76835) (xy -0.1651 0.7366) (xy -0.1651 0.44958)
						(xy -0.17272 0.44196) (xy -0.19812 0.4064) (xy -0.2032 0.39624) (xy -0.20701 0.38735) (xy -0.21209 0.37719)
						(xy -0.2159 0.36703) (xy -0.21844 0.35687) (xy -0.22225 0.34544) (xy -0.22352 0.33528) (xy -0.22606 0.32512)
						(xy -0.22733 0.31369) (xy -0.22733 0.30353) (xy -0.2286 0.2921) (xy -0.22733 0.28067) (xy -0.22733 0.27051)
						(xy -0.22606 0.25908) (xy -0.22352 0.24892) (xy -0.22225 0.23876) (xy -0.21844 0.22733) (xy -0.2159 0.21717)
						(xy -0.21209 0.20701) (xy -0.20701 0.19685) (xy -0.2032 0.18796) (xy -0.19812 0.1778) (xy -0.17272 0.14224)
						(xy -0.1651 0.13462) (xy -0.1651 -0.7366) (xy -0.16256 -0.76835) (xy -0.1524 -0.8001) (xy -0.13716 -0.82804)
						(xy -0.11684 -0.85344) (xy -0.09144 -0.87376) (xy -0.0635 -0.889) (xy -0.03175 -0.89916) (xy 0 -0.9017)
						(xy 0.03175 -0.89916) (xy 0.0635 -0.889) (xy 0.09144 -0.87376) (xy 0.11684 -0.85344) (xy 0.13716 -0.82804)
						(xy 0.1524 -0.8001) (xy 0.16256 -0.76835) (xy 0.1651 -0.7366) (xy 0.1651 0.13462) (xy 0.17272 0.14224)
						(xy 0.19812 0.1778) (xy 0.2032 0.18796) (xy 0.20701 0.19685) (xy 0.21209 0.20701) (xy 0.2159 0.21717)
						(xy 0.21844 0.22733) (xy 0.22225 0.23876) (xy 0.22352 0.24892) (xy 0.22606 0.25908) (xy 0.22733 0.27051)
						(xy 0.22733 0.28067) (xy 0.2286 0.2921) (xy 0.22733 0.30353) (xy 0.22733 0.31369) (xy 0.22606 0.32512)
						(xy 0.22352 0.33528) (xy 0.22225 0.34544) (xy 0.21844 0.35687) (xy 0.2159 0.36703) (xy 0.21209 0.37719)
						(xy 0.20701 0.38735) (xy 0.2032 0.39624) (xy 0.19812 0.4064) (xy 0.17272 0.44196) (xy 0.1651 0.44958)
						(xy 0.1651 0.7366) (xy 0.16256 0.76835) (xy 0.1524 0.8001) (xy 0.13716 0.82804) (xy 0.11684 0.85344)
						(xy 0.09144 0.87376) (xy 0.0635 0.889) (xy 0.03175 0.89916)
					)
					(width 0)
					(fill yes)
				)
			)
		)
		(pad "3" smd custom
			(at -31.049976 4.106672)
			(size 0.1143 0.1143)
			(layers "F.Cu" "F.Mask" "F.Paste")
			(net "GND")
			(options
				(clearance outline)
				(anchor circle)
			)
			(primitives
				(gr_poly
					(pts
						(xy 0 0.9017) (xy -0.03175 0.89916) (xy -0.0635 0.889) (xy -0.09144 0.87376) (xy -0.11684 0.85344)
						(xy -0.13716 0.82804) (xy -0.1524 0.8001) (xy -0.16256 0.76835) (xy -0.1651 0.7366) (xy -0.1651 0.11938)
						(xy -0.17272 0.11176) (xy -0.19812 0.0762) (xy -0.2032 0.06604) (xy -0.20701 0.05715) (xy -0.21209 0.04699)
						(xy -0.2159 0.03683) (xy -0.21844 0.02667) (xy -0.22225 0.01524) (xy -0.22352 0.00508) (xy -0.22606 -0.00508)
						(xy -0.22733 -0.01651) (xy -0.22733 -0.02667) (xy -0.2286 -0.0381) (xy -0.22733 -0.04953) (xy -0.22733 -0.05969)
						(xy -0.22606 -0.07112) (xy -0.22352 -0.08128) (xy -0.22225 -0.09144) (xy -0.21844 -0.10287) (xy -0.2159 -0.11303)
						(xy -0.21209 -0.12319) (xy -0.20701 -0.13335) (xy -0.2032 -0.14224) (xy -0.19812 -0.1524) (xy -0.17272 -0.18796)
						(xy -0.1651 -0.19558) (xy -0.1651 -0.7366) (xy -0.16256 -0.76835) (xy -0.1524 -0.8001) (xy -0.13716 -0.82804)
						(xy -0.11684 -0.85344) (xy -0.09144 -0.87376) (xy -0.0635 -0.889) (xy -0.03175 -0.89916) (xy 0 -0.9017)
						(xy 0.03175 -0.89916) (xy 0.0635 -0.889) (xy 0.09144 -0.87376) (xy 0.11684 -0.85344) (xy 0.13716 -0.82804)
						(xy 0.1524 -0.8001) (xy 0.16256 -0.76835) (xy 0.1651 -0.7366) (xy 0.1651 -0.19685) (xy 0.17272 -0.18923)
						(xy 0.17907 -0.18034) (xy 0.18669 -0.17145) (xy 0.19177 -0.16256) (xy 0.19812 -0.15367) (xy 0.20828 -0.13335)
						(xy 0.21971 -0.10287) (xy 0.22225 -0.09271) (xy 0.22479 -0.08128) (xy 0.22606 -0.07112) (xy 0.2286 -0.05969)
						(xy 0.2286 -0.01651) (xy 0.22606 -0.00508) (xy 0.22479 0.00508) (xy 0.22225 0.01651) (xy 0.21971 0.02667)
						(xy 0.20828 0.05715) (xy 0.19812 0.07747) (xy 0.19177 0.08636) (xy 0.18669 0.09525) (xy 0.17907 0.10414)
						(xy 0.17272 0.11303) (xy 0.1651 0.12065) (xy 0.1651 0.7366) (xy 0.16256 0.76835) (xy 0.1524 0.8001)
						(xy 0.13716 0.82804) (xy 0.11684 0.85344) (xy 0.09144 0.87376) (xy 0.0635 0.889) (xy 0.03175 0.89916)
					)
					(width 0)
					(fill yes)
				)
			)
		)
		(pad "4" smd custom
			(at -30.750002 -4.106672)
			(size 0.1143 0.1143)
			(layers "F.Cu" "F.Mask" "F.Paste")
			(net "M_B_DQ0")
			(options
				(clearance outline)
				(anchor circle)
			)
			(primitives
				(gr_poly
					(pts
						(xy 0 0.9017) (xy -0.03175 0.89916) (xy -0.0635 0.889) (xy -0.09144 0.87376) (xy -0.11684 0.85344)
						(xy -0.13716 0.82804) (xy -0.1524 0.8001) (xy -0.16256 0.76835) (xy -0.1651 0.7366) (xy -0.1651 0.19685)
						(xy -0.17272 0.18923) (xy -0.17907 0.18034) (xy -0.18669 0.17145) (xy -0.19177 0.16256) (xy -0.19812 0.15367)
						(xy -0.20828 0.13335) (xy -0.21971 0.10287) (xy -0.22225 0.09271) (xy -0.22479 0.08128) (xy -0.22606 0.07112)
						(xy -0.2286 0.05969) (xy -0.2286 0.01651) (xy -0.22606 0.00508) (xy -0.22479 -0.00508) (xy -0.22225 -0.01651)
						(xy -0.21971 -0.02667) (xy -0.20828 -0.05715) (xy -0.19812 -0.07747) (xy -0.19177 -0.08636) (xy -0.18669 -0.09525)
						(xy -0.17907 -0.10414) (xy -0.17272 -0.11303) (xy -0.1651 -0.12065) (xy -0.1651 -0.7366) (xy -0.16256 -0.76835)
						(xy -0.1524 -0.8001) (xy -0.13716 -0.82804) (xy -0.11684 -0.85344) (xy -0.09144 -0.87376) (xy -0.0635 -0.889)
						(xy -0.03175 -0.89916) (xy 0 -0.9017) (xy 0.03175 -0.89916) (xy 0.0635 -0.889) (xy 0.09144 -0.87376)
						(xy 0.11684 -0.85344) (xy 0.13716 -0.82804) (xy 0.1524 -0.8001) (xy 0.16256 -0.76835) (xy 0.1651 -0.7366)
						(xy 0.1651 -0.11938) (xy 0.17272 -0.11176) (xy 0.19812 -0.0762) (xy 0.2032 -0.06604) (xy 0.20701 -0.05715)
						(xy 0.21209 -0.04699) (xy 0.2159 -0.03683) (xy 0.21844 -0.02667) (xy 0.22225 -0.01524) (xy 0.22352 -0.00508)
						(xy 0.22606 0.00508) (xy 0.22733 0.01651) (xy 0.22733 0.02667) (xy 0.2286 0.0381) (xy 0.22733 0.04953)
						(xy 0.22733 0.05969) (xy 0.22606 0.07112) (xy 0.22352 0.08128) (xy 0.22225 0.09144) (xy 0.21844 0.10287)
						(xy 0.2159 0.11303) (xy 0.21209 0.12319) (xy 0.20701 0.13335) (xy 0.2032 0.14224) (xy 0.19812 0.1524)
						(xy 0.17272 0.18796) (xy 0.1651 0.19558) (xy 0.1651 0.7366) (xy 0.16256 0.76835) (xy 0.1524 0.8001)
						(xy 0.13716 0.82804) (xy 0.11684 0.85344) (xy 0.09144 0.87376) (xy 0.0635 0.889) (xy 0.03175 0.89916)
					)
					(width 0)
					(fill yes)
				)
			)
		)
		(pad "5" smd custom
			(at -30.450028 4.106672)
			(size 0.1143 0.1143)
			(layers "F.Cu" "F.Mask" "F.Paste")
			(net "M_B_DQ4")
			(options
				(clearance outline)
				(anchor circle)
			)
			(primitives
				(gr_poly
					(pts
						(xy 0 0.9017) (xy -0.03175 0.89916) (xy -0.0635 0.889) (xy -0.09144 0.87376) (xy -0.11684 0.85344)
						(xy -0.13716 0.82804) (xy -0.1524 0.8001) (xy -0.16256 0.76835) (xy -0.1651 0.7366) (xy -0.1651 -0.13462)
						(xy -0.17272 -0.14224) (xy -0.19812 -0.1778) (xy -0.2032 -0.18796) (xy -0.20701 -0.19685) (xy -0.21209 -0.20701)
						(xy -0.2159 -0.21717) (xy -0.21844 -0.22733) (xy -0.22225 -0.23876) (xy -0.22352 -0.24892) (xy -0.22606 -0.25908)
						(xy -0.22733 -0.27051) (xy -0.22733 -0.28067) (xy -0.2286 -0.2921) (xy -0.22733 -0.30353) (xy -0.22733 -0.31369)
						(xy -0.22606 -0.32512) (xy -0.22352 -0.33528) (xy -0.22225 -0.34544) (xy -0.21844 -0.35687) (xy -0.2159 -0.36703)
						(xy -0.21209 -0.37719) (xy -0.20701 -0.38735) (xy -0.2032 -0.39624) (xy -0.19812 -0.4064) (xy -0.17272 -0.44196)
						(xy -0.1651 -0.44958) (xy -0.1651 -0.7366) (xy -0.16256 -0.76835) (xy -0.1524 -0.8001) (xy -0.13716 -0.82804)
						(xy -0.11684 -0.85344) (xy -0.09144 -0.87376) (xy -0.0635 -0.889) (xy -0.03175 -0.89916) (xy 0 -0.9017)
						(xy 0.03175 -0.89916) (xy 0.0635 -0.889) (xy 0.09144 -0.87376) (xy 0.11684 -0.85344) (xy 0.13716 -0.82804)
						(xy 0.1524 -0.8001) (xy 0.16256 -0.76835) (xy 0.1651 -0.7366) (xy 0.1651 -0.44958) (xy 0.17272 -0.44196)
						(xy 0.19812 -0.4064) (xy 0.2032 -0.39624) (xy 0.20701 -0.38735) (xy 0.21209 -0.37719) (xy 0.2159 -0.36703)
						(xy 0.21844 -0.35687) (xy 0.22225 -0.34544) (xy 0.22352 -0.33528) (xy 0.22606 -0.32512) (xy 0.22733 -0.31369)
						(xy 0.22733 -0.30353) (xy 0.2286 -0.2921) (xy 0.22733 -0.28067) (xy 0.22733 -0.27051) (xy 0.22606 -0.25908)
						(xy 0.22352 -0.24892) (xy 0.22225 -0.23876) (xy 0.21844 -0.22733) (xy 0.2159 -0.21717) (xy 0.21209 -0.20701)
						(xy 0.20701 -0.19685) (xy 0.2032 -0.18796) (xy 0.19812 -0.1778) (xy 0.17272 -0.14224) (xy 0.1651 -0.13462)
						(xy 0.1651 0.7366) (xy 0.16256 0.76835) (xy 0.1524 0.8001) (xy 0.13716 0.82804) (xy 0.11684 0.85344)
						(xy 0.09144 0.87376) (xy 0.0635 0.889) (xy 0.03175 0.89916)
					)
					(width 0)
					(fill yes)
				)
			)
		)
		(pad "6" smd custom
			(at -30.150054 -4.106672)
			(size 0.1143 0.1143)
			(layers "F.Cu" "F.Mask" "F.Paste")
			(net "M_B_DQ1")
			(options
				(clearance outline)
				(anchor circle)
			)
			(primitives
				(gr_poly
					(pts
						(xy 0 0.9017) (xy -0.03175 0.89916) (xy -0.0635 0.889) (xy -0.09144 0.87376) (xy -0.11684 0.85344)
						(xy -0.13716 0.82804) (xy -0.1524 0.8001) (xy -0.16256 0.76835) (xy -0.1651 0.7366) (xy -0.1651 0.44958)
						(xy -0.17272 0.44196) (xy -0.19812 0.4064) (xy -0.2032 0.39624) (xy -0.20701 0.38735) (xy -0.21209 0.37719)
						(xy -0.2159 0.36703) (xy -0.21844 0.35687) (xy -0.22225 0.34544) (xy -0.22352 0.33528) (xy -0.22606 0.32512)
						(xy -0.22733 0.31369) (xy -0.22733 0.30353) (xy -0.2286 0.2921) (xy -0.22733 0.28067) (xy -0.22733 0.27051)
						(xy -0.22606 0.25908) (xy -0.22352 0.24892) (xy -0.22225 0.23876) (xy -0.21844 0.22733) (xy -0.2159 0.21717)
						(xy -0.21209 0.20701) (xy -0.20701 0.19685) (xy -0.2032 0.18796) (xy -0.19812 0.1778) (xy -0.17272 0.14224)
						(xy -0.1651 0.13462) (xy -0.1651 -0.7366) (xy -0.16256 -0.76835) (xy -0.1524 -0.8001) (xy -0.13716 -0.82804)
						(xy -0.11684 -0.85344) (xy -0.09144 -0.87376) (xy -0.0635 -0.889) (xy -0.03175 -0.89916) (xy 0 -0.9017)
						(xy 0.03175 -0.89916) (xy 0.0635 -0.889) (xy 0.09144 -0.87376) (xy 0.11684 -0.85344) (xy 0.13716 -0.82804)
						(xy 0.1524 -0.8001) (xy 0.16256 -0.76835) (xy 0.1651 -0.7366) (xy 0.1651 0.13462) (xy 0.17272 0.14224)
						(xy 0.19812 0.1778) (xy 0.2032 0.18796) (xy 0.20701 0.19685) (xy 0.21209 0.20701) (xy 0.2159 0.21717)
						(xy 0.21844 0.22733) (xy 0.22225 0.23876) (xy 0.22352 0.24892) (xy 0.22606 0.25908) (xy 0.22733 0.27051)
						(xy 0.22733 0.28067) (xy 0.2286 0.2921) (xy 0.22733 0.30353) (xy 0.22733 0.31369) (xy 0.22606 0.32512)
						(xy 0.22352 0.33528) (xy 0.22225 0.34544) (xy 0.21844 0.35687) (xy 0.2159 0.36703) (xy 0.21209 0.37719)
						(xy 0.20701 0.38735) (xy 0.2032 0.39624) (xy 0.19812 0.4064) (xy 0.17272 0.44196) (xy 0.1651 0.44958)
						(xy 0.1651 0.7366) (xy 0.16256 0.76835) (xy 0.1524 0.8001) (xy 0.13716 0.82804) (xy 0.11684 0.85344)
						(xy 0.09144 0.87376) (xy 0.0635 0.889) (xy 0.03175 0.89916)
					)
					(width 0)
					(fill yes)
				)
			)
		)
	)
)
